(kicad_pcb
	(version 20260206)
	(generator "pcbnew")
	(generator_version "10.0")
	(general
		(thickness 1.6)
		(legacy_teardrops no)
	)
	(paper "A4")
	(title_block
		(title "baseboard — 13948-1b.1110WZS1818.brd")
		(comment 1 "Honey Badger (Wiwynn) / footprint 852 of 2523 (SU2), pads 607-730 of 896")
	)
	(layers
		(0 "F.Cu" signal "TOP")
		(4 "In1.Cu" signal "L2GND")
		(6 "In2.Cu" signal "L3")
		(8 "In3.Cu" signal "L4VCC")
		(10 "In4.Cu" signal "L5VCC")
		(12 "In5.Cu" signal "L6")
		(14 "In6.Cu" signal "L7GND")
		(2 "B.Cu" signal "BOTTOM")
		(9 "F.Adhes" user "F.Adhesive")
		(11 "B.Adhes" user "B.Adhesive")
		(13 "F.Paste" user "Package Geometry/Pastemask Top")
		(15 "B.Paste" user "Package Geometry/Pastemask Bottom")
		(5 "F.SilkS" user "Ref Des/Silkscreen Top")
		(7 "B.SilkS" user "Ref Des/Silkscreen Bottom")
		(1 "F.Mask" user "Board Geometry/Soldermask Top")
		(3 "B.Mask" user "Board Geometry/Soldermask Bottom")
		(17 "Dwgs.User" user "User.Drawings")
		(19 "Cmts.User" user "User.Comments")
		(21 "Eco1.User" user "User.Eco1")
		(23 "Eco2.User" user "User.Eco2")
		(25 "Edge.Cuts" user "Board Geometry/Outline")
		(27 "Margin" user)
		(31 "F.CrtYd" user "Package Geometry/Place Bound Top")
		(29 "B.CrtYd" user "Package Geometry/Place Bound Bottom")
		(35 "F.Fab" user "Ref Des/Assembly Top")
		(33 "B.Fab" user "Ref Des/Assembly Bottom")
	)
	(footprint ""
		(layer "F.Cu")
		(at 102.350062 -44.99991)
		(property "Reference" "SU2"
			(at 0 0 0)
			(layer "F.SilkS")
			(hide yes)
			(effects
				(font
					(size 1.27 1.27)
				)
			)
		)
		(property "Value" "SAS3008C0-1-DB-500020657-1-GP"
			(at -20.374102 -5.0292 0)
			(unlocked yes)
			(layer "F.Fab")
			(hide yes)
			(effects
				(font
					(size 1.016 1.016)
					(thickness 0.1524)
				)
			)
		)
		(property "Device Type" "BGA896D25H78"
			(at -20.374102 -6.5532 0)
			(unlocked yes)
			(layer "F.Fab")
			(hide yes)
			(effects
				(font
					(size 1.016 1.016)
					(thickness 0.1524)
				)
			)
		)
		(duplicate_pad_numbers_are_jumpers no)
		(pad "L11" smd circle
			(at -3.599942 -3.599942)
			(size 0.3556 0.3556)
			(layers "F.Cu" "F.Mask" "F.Paste")
			(net "GND")
		)
		(pad "L12" smd circle
			(at -2.800096 -3.599942)
			(size 0.3556 0.3556)
			(layers "F.Cu" "F.Mask" "F.Paste")
			(net "GND")
		)
		(pad "L13" smd circle
			(at -1.999996 -3.599942)
			(size 0.3556 0.3556)
			(layers "F.Cu" "F.Mask" "F.Paste")
			(net "GND")
		)
		(pad "L14" smd circle
			(at -1.199896 -3.599942)
			(size 0.3556 0.3556)
			(layers "F.Cu" "F.Mask" "F.Paste")
			(net "P0V955_C")
		)
		(pad "L15" smd circle
			(at -0.40005 -3.599942)
			(size 0.3556 0.3556)
			(layers "F.Cu" "F.Mask" "F.Paste")
			(net "GND")
		)
		(pad "L16" smd circle
			(at 0.40005 -3.599942)
			(size 0.3556 0.3556)
			(layers "F.Cu" "F.Mask" "F.Paste")
			(net "P0V955_C")
		)
		(pad "L17" smd circle
			(at 1.199896 -3.599942)
			(size 0.3556 0.3556)
			(layers "F.Cu" "F.Mask" "F.Paste")
			(net "GND")
		)
		(pad "L18" smd circle
			(at 1.999996 -3.599942)
			(size 0.3556 0.3556)
			(layers "F.Cu" "F.Mask" "F.Paste")
			(net "P0V955_C")
		)
		(pad "L19" smd circle
			(at 2.800096 -3.599942)
			(size 0.3556 0.3556)
			(layers "F.Cu" "F.Mask" "F.Paste")
			(net "GND")
		)
		(pad "L20" smd circle
			(at 3.599942 -3.599942)
			(size 0.3556 0.3556)
			(layers "F.Cu" "F.Mask" "F.Paste")
			(net "P0V955_C")
		)
		(pad "L21" smd circle
			(at 4.400042 -3.599942)
			(size 0.3556 0.3556)
			(layers "F.Cu" "F.Mask" "F.Paste")
			(net "GND")
		)
		(pad "L22" smd circle
			(at 5.199888 -3.599942)
			(size 0.3556 0.3556)
			(layers "F.Cu" "F.Mask" "F.Paste")
			(net "VDDIO_15")
		)
		(pad "L23" smd circle
			(at 5.999988 -3.599942)
			(size 0.3556 0.3556)
			(layers "F.Cu" "F.Mask" "F.Paste")
			(net "GND")
		)
		(pad "L24" smd circle
			(at 6.800088 -3.599942)
			(size 0.3556 0.3556)
			(layers "F.Cu" "F.Mask" "F.Paste")
			(net "GND")
		)
		(pad "L25" smd circle
			(at 7.599934 -3.599942)
			(size 0.3556 0.3556)
			(layers "F.Cu" "F.Mask" "F.Paste")
			(net "GND")
		)
		(pad "L26" smd circle
			(at 8.400034 -3.599942)
			(size 0.3556 0.3556)
			(layers "F.Cu" "F.Mask" "F.Paste")
			(net "GND")
		)
		(pad "L27" smd circle
			(at 9.19988 -3.599942)
			(size 0.3556 0.3556)
			(layers "F.Cu" "F.Mask" "F.Paste")
			(net "P1V8_C")
		)
		(pad "L28" smd circle
			(at 9.99998 -3.599942)
			(size 0.3556 0.3556)
			(layers "F.Cu" "F.Mask" "F.Paste")
			(net "GND")
		)
		(pad "L29" smd circle
			(at 10.80008 -3.599942)
			(size 0.3556 0.3556)
			(layers "F.Cu" "F.Mask" "F.Paste")
			(net "XM_DATA_4")
		)
		(pad "L30" smd circle
			(at 11.599926 -3.599942)
			(size 0.3556 0.3556)
			(layers "F.Cu" "F.Mask" "F.Paste")
			(net "XM_DATA_3")
		)
		(pad "M1" smd circle
			(at -11.599926 -2.800096)
			(size 0.3556 0.3556)
			(layers "F.Cu" "F.Mask" "F.Paste")
			(net "SIO_CLK_0")
		)
		(pad "M2" smd circle
			(at -10.80008 -2.800096)
			(size 0.3556 0.3556)
			(layers "F.Cu" "F.Mask" "F.Paste")
			(net "SIO_DOUT_1")
		)
		(pad "M3" smd circle
			(at -9.99998 -2.800096)
			(size 0.3556 0.3556)
			(layers "F.Cu" "F.Mask" "F.Paste")
			(net "SIO_LOAD_0")
		)
		(pad "M4" smd circle
			(at -9.19988 -2.800096)
			(size 0.3556 0.3556)
			(layers "F.Cu" "F.Mask" "F.Paste")
			(net "P1V8_C")
		)
		(pad "M5" smd circle
			(at -8.400034 -2.800096)
			(size 0.3556 0.3556)
			(layers "F.Cu" "F.Mask" "F.Paste")
			(net "GND")
		)
		(pad "M6" smd circle
			(at -7.599934 -2.800096)
			(size 0.3556 0.3556)
			(layers "F.Cu" "F.Mask" "F.Paste")
			(net "ICE_SEL")
		)
		(pad "M7" smd circle
			(at -6.800088 -2.800096)
			(size 0.3556 0.3556)
			(layers "F.Cu" "F.Mask" "F.Paste")
			(net "GND")
		)
		(pad "M8" smd circle
			(at -5.999988 -2.800096)
			(size 0.3556 0.3556)
			(layers "F.Cu" "F.Mask" "F.Paste")
			(net "GND")
		)
		(pad "M9" smd circle
			(at -5.199888 -2.800096)
			(size 0.3556 0.3556)
			(layers "F.Cu" "F.Mask" "F.Paste")
			(net "P1V8_C")
		)
		(pad "M10" smd circle
			(at -4.400042 -2.800096)
			(size 0.3556 0.3556)
			(layers "F.Cu" "F.Mask" "F.Paste")
			(net "GND")
		)
		(pad "M11" smd circle
			(at -3.599942 -2.800096)
			(size 0.3556 0.3556)
			(layers "F.Cu" "F.Mask" "F.Paste")
			(net "P0V955_C")
		)
		(pad "M12" smd circle
			(at -2.800096 -2.800096)
			(size 0.3556 0.3556)
			(layers "F.Cu" "F.Mask" "F.Paste")
			(net "GND")
		)
		(pad "M13" smd circle
			(at -1.999996 -2.800096)
			(size 0.3556 0.3556)
			(layers "F.Cu" "F.Mask" "F.Paste")
			(net "P0V955_C")
		)
		(pad "M14" smd circle
			(at -1.199896 -2.800096)
			(size 0.3556 0.3556)
			(layers "F.Cu" "F.Mask" "F.Paste")
			(net "GND")
		)
		(pad "M15" smd circle
			(at -0.40005 -2.800096)
			(size 0.3556 0.3556)
			(layers "F.Cu" "F.Mask" "F.Paste")
			(net "P0V955_C")
		)
		(pad "M16" smd circle
			(at 0.40005 -2.800096)
			(size 0.3556 0.3556)
			(layers "F.Cu" "F.Mask" "F.Paste")
			(net "GND")
		)
		(pad "M17" smd circle
			(at 1.199896 -2.800096)
			(size 0.3556 0.3556)
			(layers "F.Cu" "F.Mask" "F.Paste")
			(net "P0V955_C")
		)
		(pad "M18" smd circle
			(at 1.999996 -2.800096)
			(size 0.3556 0.3556)
			(layers "F.Cu" "F.Mask" "F.Paste")
			(net "GND")
		)
		(pad "M19" smd circle
			(at 2.800096 -2.800096)
			(size 0.3556 0.3556)
			(layers "F.Cu" "F.Mask" "F.Paste")
			(net "P0V955_C")
		)
		(pad "M20" smd circle
			(at 3.599942 -2.800096)
			(size 0.3556 0.3556)
			(layers "F.Cu" "F.Mask" "F.Paste")
			(net "GND")
		)
		(pad "M21" smd circle
			(at 4.400042 -2.800096)
			(size 0.3556 0.3556)
			(layers "F.Cu" "F.Mask" "F.Paste")
			(net "P0V955_C")
		)
		(pad "M22" smd circle
			(at 5.199888 -2.800096)
			(size 0.3556 0.3556)
			(layers "F.Cu" "F.Mask" "F.Paste")
			(net "GND")
		)
		(pad "M23" smd circle
			(at 5.999988 -2.800096)
			(size 0.3556 0.3556)
			(layers "F.Cu" "F.Mask" "F.Paste")
			(net "GND")
		)
		(pad "M24" smd circle
			(at 6.800088 -2.800096)
			(size 0.3556 0.3556)
			(layers "F.Cu" "F.Mask" "F.Paste")
			(net "GND")
		)
		(pad "M25" smd circle
			(at 7.599934 -2.800096)
			(size 0.3556 0.3556)
			(layers "F.Cu" "F.Mask" "F.Paste")
			(net "GND")
		)
		(pad "M26" smd circle
			(at 8.400034 -2.800096)
			(size 0.3556 0.3556)
			(layers "F.Cu" "F.Mask" "F.Paste")
			(net "GND")
		)
		(pad "M27" smd circle
			(at 9.19988 -2.800096)
			(size 0.3556 0.3556)
			(layers "F.Cu" "F.Mask" "F.Paste")
			(net "GND")
		)
		(pad "M28" smd circle
			(at 9.99998 -2.800096)
			(size 0.3556 0.3556)
			(layers "F.Cu" "F.Mask" "F.Paste")
			(net "GND")
		)
		(pad "M29" smd circle
			(at 10.80008 -2.800096)
			(size 0.3556 0.3556)
			(layers "F.Cu" "F.Mask" "F.Paste")
			(net "GND")
		)
		(pad "M30" smd circle
			(at 11.599926 -2.800096)
			(size 0.3556 0.3556)
			(layers "F.Cu" "F.Mask" "F.Paste")
			(net "GND")
		)
		(pad "N1" smd circle
			(at -11.599926 -1.999996)
			(size 0.3556 0.3556)
			(layers "F.Cu" "F.Mask" "F.Paste")
			(net "GND")
		)
		(pad "N2" smd circle
			(at -10.80008 -1.999996)
			(size 0.3556 0.3556)
			(layers "F.Cu" "F.Mask" "F.Paste")
			(net "GND")
		)
		(pad "N3" smd circle
			(at -9.99998 -1.999996)
			(size 0.3556 0.3556)
			(layers "F.Cu" "F.Mask" "F.Paste")
			(net "P1V8_C")
		)
		(pad "N4" smd circle
			(at -9.19988 -1.999996)
			(size 0.3556 0.3556)
			(layers "F.Cu" "F.Mask" "F.Paste")
			(net "GND")
		)
		(pad "N5" smd circle
			(at -8.400034 -1.999996)
			(size 0.3556 0.3556)
			(layers "F.Cu" "F.Mask" "F.Paste")
			(net "Net_1068")
		)
		(pad "N6" smd circle
			(at -7.599934 -1.999996)
			(size 0.3556 0.3556)
			(layers "F.Cu" "F.Mask" "F.Paste")
			(net "Net_1069")
		)
		(pad "N7" smd circle
			(at -6.800088 -1.999996)
			(size 0.3556 0.3556)
			(layers "F.Cu" "F.Mask" "F.Paste")
			(net "GND")
		)
		(pad "N8" smd circle
			(at -5.999988 -1.999996)
			(size 0.3556 0.3556)
			(layers "F.Cu" "F.Mask" "F.Paste")
			(net "GND")
		)
		(pad "N9" smd circle
			(at -5.199888 -1.999996)
			(size 0.3556 0.3556)
			(layers "F.Cu" "F.Mask" "F.Paste")
			(net "GND")
		)
		(pad "N10" smd circle
			(at -4.400042 -1.999996)
			(size 0.3556 0.3556)
			(layers "F.Cu" "F.Mask" "F.Paste")
			(net "GND")
		)
		(pad "N11" smd circle
			(at -3.599942 -1.999996)
			(size 0.3556 0.3556)
			(layers "F.Cu" "F.Mask" "F.Paste")
			(net "GND")
		)
		(pad "N12" smd circle
			(at -2.800096 -1.999996)
			(size 0.3556 0.3556)
			(layers "F.Cu" "F.Mask" "F.Paste")
			(net "P0V955_C")
		)
		(pad "N13" smd circle
			(at -1.999996 -1.999996)
			(size 0.3556 0.3556)
			(layers "F.Cu" "F.Mask" "F.Paste")
			(net "GND")
		)
		(pad "N14" smd circle
			(at -1.199896 -1.999996)
			(size 0.3556 0.3556)
			(layers "F.Cu" "F.Mask" "F.Paste")
			(net "P0V955_C")
		)
		(pad "N15" smd circle
			(at -0.40005 -1.999996)
			(size 0.3556 0.3556)
			(layers "F.Cu" "F.Mask" "F.Paste")
			(net "GND")
		)
		(pad "N16" smd circle
			(at 0.40005 -1.999996)
			(size 0.3556 0.3556)
			(layers "F.Cu" "F.Mask" "F.Paste")
			(net "P0V955_C")
		)
		(pad "N17" smd circle
			(at 1.199896 -1.999996)
			(size 0.3556 0.3556)
			(layers "F.Cu" "F.Mask" "F.Paste")
			(net "GND")
		)
		(pad "N18" smd circle
			(at 1.999996 -1.999996)
			(size 0.3556 0.3556)
			(layers "F.Cu" "F.Mask" "F.Paste")
			(net "P0V955_C")
		)
		(pad "N19" smd circle
			(at 2.800096 -1.999996)
			(size 0.3556 0.3556)
			(layers "F.Cu" "F.Mask" "F.Paste")
			(net "GND")
		)
		(pad "N20" smd circle
			(at 3.599942 -1.999996)
			(size 0.3556 0.3556)
			(layers "F.Cu" "F.Mask" "F.Paste")
			(net "P0V955_C")
		)
		(pad "N21" smd circle
			(at 4.400042 -1.999996)
			(size 0.3556 0.3556)
			(layers "F.Cu" "F.Mask" "F.Paste")
			(net "GND")
		)
		(pad "N22" smd circle
			(at 5.199888 -1.999996)
			(size 0.3556 0.3556)
			(layers "F.Cu" "F.Mask" "F.Paste")
			(net "GND")
		)
		(pad "N23" smd circle
			(at 5.999988 -1.999996)
			(size 0.3556 0.3556)
			(layers "F.Cu" "F.Mask" "F.Paste")
			(net "GND")
		)
		(pad "N24" smd circle
			(at 6.800088 -1.999996)
			(size 0.3556 0.3556)
			(layers "F.Cu" "F.Mask" "F.Paste")
			(net "GND")
		)
		(pad "N25" smd circle
			(at 7.599934 -1.999996)
			(size 0.3556 0.3556)
			(layers "F.Cu" "F.Mask" "F.Paste")
			(net "GND")
		)
		(pad "N26" smd circle
			(at 8.400034 -1.999996)
			(size 0.3556 0.3556)
			(layers "F.Cu" "F.Mask" "F.Paste")
			(net "GND")
		)
		(pad "N27" smd circle
			(at 9.19988 -1.999996)
			(size 0.3556 0.3556)
			(layers "F.Cu" "F.Mask" "F.Paste")
			(net "P1V8_C")
		)
		(pad "N28" smd circle
			(at 9.99998 -1.999996)
			(size 0.3556 0.3556)
			(layers "F.Cu" "F.Mask" "F.Paste")
			(net "IOC_GPIO_32")
		)
		(pad "N29" smd circle
			(at 10.80008 -1.999996)
			(size 0.3556 0.3556)
			(layers "F.Cu" "F.Mask" "F.Paste")
			(net "MEM_CLK_SEL")
		)
		(pad "N30" smd circle
			(at 11.599926 -1.999996)
			(size 0.3556 0.3556)
			(layers "F.Cu" "F.Mask" "F.Paste")
			(net "SBL_SDA")
		)
		(pad "P1" smd circle
			(at -11.599926 -1.199896)
			(size 0.3556 0.3556)
			(layers "F.Cu" "F.Mask" "F.Paste")
			(net "IOC_REF_CLK_P")
		)
		(pad "P2" smd circle
			(at -10.80008 -1.199896)
			(size 0.3556 0.3556)
			(layers "F.Cu" "F.Mask" "F.Paste")
			(net "IOC_REF_CLK_N")
		)
		(pad "P3" smd circle
			(at -9.99998 -1.199896)
			(size 0.3556 0.3556)
			(layers "F.Cu" "F.Mask" "F.Paste")
			(net "GND")
		)
		(pad "P4" smd circle
			(at -9.19988 -1.199896)
			(size 0.3556 0.3556)
			(layers "F.Cu" "F.Mask" "F.Paste")
			(net "P1V8_C")
		)
		(pad "P5" smd circle
			(at -8.400034 -1.199896)
			(size 0.3556 0.3556)
			(layers "F.Cu" "F.Mask" "F.Paste")
			(net "Net_1070")
		)
		(pad "P6" smd circle
			(at -7.599934 -1.199896)
			(size 0.3556 0.3556)
			(layers "F.Cu" "F.Mask" "F.Paste")
			(net "Net_1071")
		)
		(pad "P7" smd circle
			(at -6.800088 -1.199896)
			(size 0.3556 0.3556)
			(layers "F.Cu" "F.Mask" "F.Paste")
			(net "GND")
		)
		(pad "P8" smd circle
			(at -5.999988 -1.199896)
			(size 0.3556 0.3556)
			(layers "F.Cu" "F.Mask" "F.Paste")
			(net "GND")
		)
		(pad "P9" smd circle
			(at -5.199888 -1.199896)
			(size 0.3556 0.3556)
			(layers "F.Cu" "F.Mask" "F.Paste")
			(net "GND")
		)
		(pad "P10" smd circle
			(at -4.400042 -1.199896)
			(size 0.3556 0.3556)
			(layers "F.Cu" "F.Mask" "F.Paste")
			(net "GND")
		)
		(pad "P11" smd circle
			(at -3.599942 -1.199896)
			(size 0.3556 0.3556)
			(layers "F.Cu" "F.Mask" "F.Paste")
			(net "GND")
		)
		(pad "P12" smd circle
			(at -2.800096 -1.199896)
			(size 0.3556 0.3556)
			(layers "F.Cu" "F.Mask" "F.Paste")
			(net "GND")
		)
		(pad "P13" smd circle
			(at -1.999996 -1.199896)
			(size 0.3556 0.3556)
			(layers "F.Cu" "F.Mask" "F.Paste")
			(net "P0V955_C")
		)
		(pad "P14" smd circle
			(at -1.199896 -1.199896)
			(size 0.3556 0.3556)
			(layers "F.Cu" "F.Mask" "F.Paste")
			(net "GND")
		)
		(pad "P15" smd circle
			(at -0.40005 -1.199896)
			(size 0.3556 0.3556)
			(layers "F.Cu" "F.Mask" "F.Paste")
			(net "P0V955_C")
		)
		(pad "P16" smd circle
			(at 0.40005 -1.199896)
			(size 0.3556 0.3556)
			(layers "F.Cu" "F.Mask" "F.Paste")
			(net "GND")
		)
		(pad "P17" smd circle
			(at 1.199896 -1.199896)
			(size 0.3556 0.3556)
			(layers "F.Cu" "F.Mask" "F.Paste")
			(net "P0V955_C")
		)
		(pad "P18" smd circle
			(at 1.999996 -1.199896)
			(size 0.3556 0.3556)
			(layers "F.Cu" "F.Mask" "F.Paste")
			(net "GND")
		)
		(pad "P19" smd circle
			(at 2.800096 -1.199896)
			(size 0.3556 0.3556)
			(layers "F.Cu" "F.Mask" "F.Paste")
			(net "P0V955_C")
		)
		(pad "P20" smd circle
			(at 3.599942 -1.199896)
			(size 0.3556 0.3556)
			(layers "F.Cu" "F.Mask" "F.Paste")
			(net "GND")
		)
		(pad "P21" smd circle
			(at 4.400042 -1.199896)
			(size 0.3556 0.3556)
			(layers "F.Cu" "F.Mask" "F.Paste")
			(net "P0V955_C")
		)
		(pad "P22" smd circle
			(at 5.199888 -1.199896)
			(size 0.3556 0.3556)
			(layers "F.Cu" "F.Mask" "F.Paste")
			(net "GND")
		)
		(pad "P23" smd circle
			(at 5.999988 -1.199896)
			(size 0.3556 0.3556)
			(layers "F.Cu" "F.Mask" "F.Paste")
			(net "GND")
		)
		(pad "P24" smd circle
			(at 6.800088 -1.199896)
			(size 0.3556 0.3556)
			(layers "F.Cu" "F.Mask" "F.Paste")
			(net "GND")
		)
		(pad "P25" smd circle
			(at 7.599934 -1.199896)
			(size 0.3556 0.3556)
			(layers "F.Cu" "F.Mask" "F.Paste")
			(net "GND")
		)
		(pad "P26" smd circle
			(at 8.400034 -1.199896)
			(size 0.3556 0.3556)
			(layers "F.Cu" "F.Mask" "F.Paste")
			(net "P1V8_C")
		)
		(pad "P27" smd circle
			(at 9.19988 -1.199896)
			(size 0.3556 0.3556)
			(layers "F.Cu" "F.Mask" "F.Paste")
			(net "GND")
		)
		(pad "P28" smd circle
			(at 9.99998 -1.199896)
			(size 0.3556 0.3556)
			(layers "F.Cu" "F.Mask" "F.Paste")
			(net "IOC_SCL_3")
		)
		(pad "P29" smd circle
			(at 10.80008 -1.199896)
			(size 0.3556 0.3556)
			(layers "F.Cu" "F.Mask" "F.Paste")
			(net "IOC_CLK_SEL0")
		)
		(pad "P30" smd circle
			(at 11.599926 -1.199896)
			(size 0.3556 0.3556)
			(layers "F.Cu" "F.Mask" "F.Paste")
			(net "IOC_SCL_1")
		)
		(pad "R1" smd circle
			(at -11.599926 -0.40005)
			(size 0.3556 0.3556)
			(layers "F.Cu" "F.Mask" "F.Paste")
			(net "GND")
		)
		(pad "R2" smd circle
			(at -10.80008 -0.40005)
			(size 0.3556 0.3556)
			(layers "F.Cu" "F.Mask" "F.Paste")
			(net "GND")
		)
		(pad "R3" smd circle
			(at -9.99998 -0.40005)
			(size 0.3556 0.3556)
			(layers "F.Cu" "F.Mask" "F.Paste")
			(net "GND")
		)
		(pad "R4" smd circle
			(at -9.19988 -0.40005)
			(size 0.3556 0.3556)
			(layers "F.Cu" "F.Mask" "F.Paste")
			(net "GND")
		)
		(pad "R5" smd circle
			(at -8.400034 -0.40005)
			(size 0.3556 0.3556)
			(layers "F.Cu" "F.Mask" "F.Paste")
			(net "IOC_SIO_BLINK")
		)
		(pad "R6" smd circle
			(at -7.599934 -0.40005)
			(size 0.3556 0.3556)
			(layers "F.Cu" "F.Mask" "F.Paste")
			(net "POWERLOSS#")
		)
		(pad "R7" smd circle
			(at -6.800088 -0.40005)
			(size 0.3556 0.3556)
			(layers "F.Cu" "F.Mask" "F.Paste")
			(net "GND")
		)
		(pad "R8" smd circle
			(at -5.999988 -0.40005)
			(size 0.3556 0.3556)
			(layers "F.Cu" "F.Mask" "F.Paste")
			(net "GND")
		)
		(pad "R9" smd circle
			(at -5.199888 -0.40005)
			(size 0.3556 0.3556)
			(layers "F.Cu" "F.Mask" "F.Paste")
			(net "GND")
		)
		(pad "R10" smd circle
			(at -4.400042 -0.40005)
			(size 0.3556 0.3556)
			(layers "F.Cu" "F.Mask" "F.Paste")
			(net "GND")
		)
		(pad "R11" smd circle
			(at -3.599942 -0.40005)
			(size 0.3556 0.3556)
			(layers "F.Cu" "F.Mask" "F.Paste")
			(net "GND")
		)
		(pad "R12" smd circle
			(at -2.800096 -0.40005)
			(size 0.3556 0.3556)
			(layers "F.Cu" "F.Mask" "F.Paste")
			(net "P0V955_C")
		)
		(pad "R13" smd circle
			(at -1.999996 -0.40005)
			(size 0.3556 0.3556)
			(layers "F.Cu" "F.Mask" "F.Paste")
			(net "GND")
		)
		(pad "R14" smd circle
			(at -1.199896 -0.40005)
			(size 0.3556 0.3556)
			(layers "F.Cu" "F.Mask" "F.Paste")
			(net "P0V955_C")
		)
	)
)
